# S9S_MB_2U (Grand Teton) — schematic netlist excerpt (pin names and nets, part order shuffled) for the footprints in the layout excerpt that follows; sources: Cadence DE-HDL packaged netlist, KiCad conversion of 03242023_DA0F0TMBIJ0_F0T_Motherboard_J_brd_V01_OCP.brd

PC2208  Q_CAP  1UF 25V 10% X6S  pkg C0402  page 192 : A = P3V3_AUX ; B = GND
PJ50  Q_SHORT  EMPTY  pkg SM  page 292 : \1\ = VSENSE_PVCCINFAON_CPU1_DP ; \2\ = SH_PVCCINFAON_CPU1

(kicad_pcb
	(version 20260206)
	(generator "pcbnew")
	(generator_version "10.0")
	(general
		(thickness 1.6)
		(legacy_teardrops no)
	)
	(paper "A4")
	(title_block
		(title "03242023_DA0F0TMBIJ0_F0T_Motherboard_J_brd_V01_OCP.brd")
		(comment 1 "Grand Teton / footprints 1583-1584 of 6105")
	)
	(layers
		(0 "F.Cu" signal "TOP")
		(4 "In1.Cu" signal "GND")
		(6 "In2.Cu" signal "IN1")
		(8 "In3.Cu" signal "GND1")
		(10 "In4.Cu" signal "IN2")
		(12 "In5.Cu" signal "GND2")
		(14 "In6.Cu" signal "IN3")
		(16 "In7.Cu" signal "GND3")
		(18 "In8.Cu" signal "VCC")
		(20 "In9.Cu" signal "VCC1")
		(22 "In10.Cu" signal "GND4")
		(24 "In11.Cu" signal "IN4")
		(26 "In12.Cu" signal "GND5")
		(28 "In13.Cu" signal "IN5")
		(30 "In14.Cu" signal "GND6")
		(32 "In15.Cu" signal "IN6")
		(34 "In16.Cu" signal "GND7")
		(2 "B.Cu" signal "BOTTOM")
		(9 "F.Adhes" user "F.Adhesive")
		(11 "B.Adhes" user "B.Adhesive")
		(13 "F.Paste" user "Package Geometry/Pastemask Top")
		(15 "B.Paste" user "Package Geometry/Pastemask Bottom")
		(5 "F.SilkS" user "Ref Des/Silkscreen Top")
		(7 "B.SilkS" user "Ref Des/Silkscreen Bottom")
		(1 "F.Mask" user "Board Geometry/Soldermask Top")
		(3 "B.Mask" user "Board Geometry/Soldermask Bottom")
		(17 "Dwgs.User" user "User.Drawings")
		(19 "Cmts.User" user "User.Comments")
		(21 "Eco1.User" user "User.Eco1")
		(23 "Eco2.User" user "User.Eco2")
		(25 "Edge.Cuts" user "Board Geometry/Outline")
		(27 "Margin" user)
		(31 "F.CrtYd" user "Package Geometry/Place Bound Top")
		(29 "B.CrtYd" user "Package Geometry/Place Bound Bottom")
		(35 "F.Fab" user "Ref Des/Assembly Top")
		(33 "B.Fab" user "Ref Des/Assembly Bottom")
	)
	(footprint ""
		(layer "F.Cu")
		(at 219.347034 -75.02779 -90)
		(property "Reference" "PC2208"
			(at 0 0 270)
			(layer "F.SilkS")
			(hide yes)
			(effects
				(font
					(size 1.27 1.27)
				)
			)
		)
		(property "Value" ""
			(at 0 0 270)
			(layer "F.Fab")
			(effects
				(font
					(size 1.27 1.27)
				)
			)
		)
		(duplicate_pad_numbers_are_jumpers no)
		(fp_line
			(start -0.7874 0.4064)
			(end -0.7874 -0.4064)
			(stroke
				(width 0.1524)
				(type default)
			)
			(layer "F.SilkS")
		)
		(fp_line
			(start 0.7874 0.4064)
			(end -0.7874 0.4064)
			(stroke
				(width 0.1524)
				(type default)
			)
			(layer "F.SilkS")
		)
		(fp_line
			(start -0.7874 -0.4064)
			(end 0.7874 -0.4064)
			(stroke
				(width 0.1524)
				(type default)
			)
			(layer "F.SilkS")
		)
		(fp_line
			(start 0.7874 -0.4064)
			(end 0.7874 0.4064)
			(stroke
				(width 0.1524)
				(type default)
			)
			(layer "F.SilkS")
		)
		(fp_line
			(start -0.67945 0.3048)
			(end -0.67945 -0.305054)
			(stroke
				(width 0.1)
				(type default)
			)
			(layer "F.Fab")
		)
		(fp_line
			(start -0.12065 0.3048)
			(end -0.67945 0.3048)
			(stroke
				(width 0.1)
				(type default)
			)
			(layer "F.Fab")
		)
		(fp_line
			(start 0.120396 0.3048)
			(end 0.120396 0.2794)
			(stroke
				(width 0.1)
				(type default)
			)
			(layer "F.Fab")
		)
		(fp_line
			(start 0.67945 0.3048)
			(end 0.120396 0.3048)
			(stroke
				(width 0.1)
				(type default)
			)
			(layer "F.Fab")
		)
		(fp_line
			(start -0.12065 0.2794)
			(end -0.12065 0.3048)
			(stroke
				(width 0.1)
				(type default)
			)
			(layer "F.Fab")
		)
		(fp_line
			(start 0.120396 0.2794)
			(end -0.12065 0.2794)
			(stroke
				(width 0.1)
				(type default)
			)
			(layer "F.Fab")
		)
		(fp_line
			(start -0.12065 -0.2794)
			(end 0.12065 -0.2794)
			(stroke
				(width 0.1)
				(type default)
			)
			(layer "F.Fab")
		)
		(fp_line
			(start 0.12065 -0.2794)
			(end 0.12065 -0.3048)
			(stroke
				(width 0.1)
				(type default)
			)
			(layer "F.Fab")
		)
		(fp_line
			(start 0.12065 -0.3048)
			(end 0.67945 -0.3048)
			(stroke
				(width 0.1)
				(type default)
			)
			(layer "F.Fab")
		)
		(fp_line
			(start 0.67945 -0.3048)
			(end 0.67945 0.3048)
			(stroke
				(width 0.1)
				(type default)
			)
			(layer "F.Fab")
		)
		(fp_line
			(start -0.67945 -0.305054)
			(end -0.12065 -0.305054)
			(stroke
				(width 0.1)
				(type default)
			)
			(layer "F.Fab")
		)
		(fp_line
			(start -0.12065 -0.305054)
			(end -0.12065 -0.2794)
			(stroke
				(width 0.1)
				(type default)
			)
			(layer "F.Fab")
		)
		(pad "1" smd circle
			(at -0.40005 0 270)
			(size 0 0)
			(layers "F.Cu" "F.Mask" "F.Paste")
			(net "P3V3_AUX")
		)
		(pad "2" smd circle
			(at 0.40005 0 270)
			(size 0 0)
			(layers "F.Cu" "F.Mask" "F.Paste")
			(net "GND")
		)
	)
	(footprint ""
		(layer "F.Cu")
		(at 35.171126 -136.386062 -90)
		(property "Reference" "PJ50"
			(at -0.650494 -1.97866 0)
			(unlocked yes)
			(layer "F.SilkS")
			(effects
				(font
					(size 0.7874 0.5842)
					(thickness 0.1524)
				)
				(justify left)
			)
		)
		(property "Value" ""
			(at 0 0 270)
			(layer "F.Fab")
			(effects
				(font
					(size 1.27 1.27)
				)
			)
		)
		(duplicate_pad_numbers_are_jumpers no)
		(pad "1" smd circle
			(at -0.7493 0)
			(size 0 0)
			(layers "F.Cu" "F.Mask" "F.Paste")
			(net "VSENSE_PVCCINFAON_CPU1_DP")
		)
		(pad "2" smd rect
			(at 0.7493 0 180)
			(size 0.7112 0.8128)
			(layers "F.Cu" "F.Mask" "F.Paste")
			(net "SH_PVCCINFAON_CPU1")
		)
		(zone
			(layer "F.Cu")
			(hatch none 0.5)
			(connect_pads
				(clearance 0)
			)
			(min_thickness 0.25)
			(keepout
				(tracks allowed)
				(vias not_allowed)
				(pads allowed)
				(copperpour not_allowed)
				(footprints allowed)
			)
			(placement
				(enabled no)
				(sheetname "")
			)
			(fill
				(thermal_gap 0.5)
				(thermal_bridge_width 0.5)
				(island_removal_mode 0)
			)
			(polygon
				(pts
					(xy 34.7599 -135.179562) (xy 35.577526 -135.179562) (xy 35.577526 -137.567162) (xy 34.7599 -137.567162)
				)
			)
		)
	)
)
